FILE_TYPE = MACRO_DRAWING;
SET COLOR_WIRE YELLOW;
SET COLOR_PROP ORANGE;
SET COLOR_DOT WHITE;
SET COLOR_ARC YELLOW;
SET COLOR_BODY GREEN;
SET COLOR_NOTE PURPLE;
SET PROP_DISPLAY VALUE;
SET PAGE_NUMBER P460;
FORCEADD PT5161LRS..1
(-7775 3750);
FORCEPROP 1 LAST LOCATION U6017
J 0
(-8125 5375);
DISPLAY 0.723404 (-8125 5375);
PAINT GREEN (-8125 5375);
FORCEPROP 0 LAST $SEC 1
J 0
(-8125 5525);
DISPLAY 0.680851 (-8125 5525);
PAINT MONO (-8125 5525);
DISPLAY INVISIBLE (-8125 5525);
FORCEPROP 0 LAST CDS_SEC 1
J 0
(-8125 5525);
DISPLAY 0.680851 (-8125 5525);
DISPLAY INVISIBLE (-8125 5525);
FORCEPROP 0 LASTPIN (-7325 4900) $PN N2
J 0
(-7315 4910);
DISPLAY 0.680851 (-7315 4910);
PAINT MONO (-7315 4910);
FORCEPROP 0 LASTPIN (-7325 4550) $PN Y2
J 0
(-7315 4560);
DISPLAY 0.680851 (-7315 4560);
PAINT MONO (-7315 4560);
FORCEPROP 0 LASTPIN (-7325 4200) $PN AG2
J 0
(-7315 4210);
DISPLAY 0.680851 (-7315 4210);
PAINT MONO (-7315 4210);
FORCEPROP 0 LASTPIN (-7325 3850) $PN AP2
J 0
(-7315 3860);
DISPLAY 0.680851 (-7315 3860);
PAINT MONO (-7315 3860);
FORCEPROP 0 LASTPIN (-7325 3500) $PN BA2
J 0
(-7315 3510);
DISPLAY 0.680851 (-7315 3510);
PAINT MONO (-7315 3510);
FORCEPROP 0 LASTPIN (-7325 3150) $PN BH2
J 0
(-7315 3160);
DISPLAY 0.680851 (-7315 3160);
PAINT MONO (-7315 3160);
FORCEPROP 0 LASTPIN (-7325 2800) $PN BR2
J 0
(-7315 2810);
DISPLAY 0.680851 (-7315 2810);
PAINT MONO (-7315 2810);
FORCEPROP 0 LASTPIN (-7325 2450) $PN CB2
J 0
(-7315 2460);
DISPLAY 0.680851 (-7315 2460);
PAINT MONO (-7315 2460);
FORCEPROP 0 LASTPIN (-7325 5000) $PN R1
J 0
(-7315 5010);
DISPLAY 0.680851 (-7315 5010);
PAINT MONO (-7315 5010);
FORCEPROP 0 LASTPIN (-7325 4650) $PN AB1
J 0
(-7315 4660);
DISPLAY 0.680851 (-7315 4660);
PAINT MONO (-7315 4660);
FORCEPROP 0 LASTPIN (-7325 4300) $PN AJ1
J 0
(-7315 4310);
DISPLAY 0.680851 (-7315 4310);
PAINT MONO (-7315 4310);
FORCEPROP 0 LASTPIN (-7325 3950) $PN AT1
J 0
(-7315 3960);
DISPLAY 0.680851 (-7315 3960);
PAINT MONO (-7315 3960);
FORCEPROP 0 LASTPIN (-7325 3600) $PN BC1
J 0
(-7315 3610);
DISPLAY 0.680851 (-7315 3610);
PAINT MONO (-7315 3610);
FORCEPROP 0 LASTPIN (-7325 3250) $PN BK1
J 0
(-7315 3260);
DISPLAY 0.680851 (-7315 3260);
PAINT MONO (-7315 3260);
FORCEPROP 0 LASTPIN (-7325 2900) $PN BU1
J 0
(-7315 2910);
DISPLAY 0.680851 (-7315 2910);
PAINT MONO (-7315 2910);
FORCEPROP 0 LASTPIN (-7325 2550) $PN CD1
J 0
(-7315 2560);
DISPLAY 0.680851 (-7315 2560);
PAINT MONO (-7315 2560);
FORCEPROP 2 LAST VALUE PT5161LRS
J 0
(-8125 5425);
DISPLAY 0.680851 (-8125 5425);
FORCEPROP 2 LAST PART_TYPE SMLF
J 0
(-8125 5475);
DISPLAY 0.680851 (-8125 5475);
FORCEPROP 1 LAST MATERIAL IC
J 0
(-8125 5225);
DISPLAY 0.723404 (-8125 5225);
PAINT GREEN (-8125 5225);
FORCEPROP 1 LAST NEEDS_NO_SIZE TRUE
J 0
(-7775 3750);
DISPLAY 0.723404 (-7775 3750);
PAINT GREEN (-7775 3750);
DISPLAY INVISIBLE (-7775 3750);
FORCEPROP 1 LAST CDS_LMAN_SYM_OUTLINE -350,1450,300,-1400
J 0
(-7775 3750);
DISPLAY 0.468085 (-7775 3750);
PAINT GREEN (-7775 3750);
DISPLAY INVISIBLE (-7775 3750);
FORCEPROP 2 LAST CDS_LIB pure_quanta
J 0
(-7775 3750);
DISPLAY INVISIBLE (-7775 3750);
FORCEPROP 1 LAST PATH I1
J 0
(-7775 3750);
DISPLAY 0.723404 (-7775 3750);
PAINT GREEN (-7775 3750);
DISPLAY INVISIBLE (-7775 3750);
FORCEPROP 1 LAST PART_NUMBER AJ051610U03
J 0
(-8125 5300);
DISPLAY 0.723404 (-8125 5300);
PAINT GREEN (-8125 5300);
DISPLAY INVISIBLE (-8125 5300);
FORCEADD TAP..1
(-6550 3500);
FORCEPROP 3 LASTPIN (-6600 3500) SIG_NAME P5E_CPU1_P3_RX_BUF_DN<11>
J 0
(-6590 3510);
DISPLAY 0.659574 (-6590 3510);
PAINT MONO (-6590 3510);
DISPLAY INVISIBLE (-6590 3510);
FORCEPROP 1 LASTPIN (-6600 3500) BN 11
J 0
(-6612 3508);
DISPLAY 0.680851 (-6612 3508);
PAINT GREEN (-6612 3508);
FORCEPROP 2 LAST CDS_LIB standard
J 0
(-6550 3500);
DISPLAY INVISIBLE (-6550 3500);
FORCEPROP 1 LAST BODY_TYPE PLUMBING
J 0
(-6550 3550);
DISPLAY 0.872340 (-6550 3550);
PAINT GREEN (-6550 3550);
DISPLAY INVISIBLE (-6550 3550);
FORCEPROP 1 LAST HDL_TAP TRUE
J 0
(-6225 3375);
DISPLAY 0.872340 (-6225 3375);
DISPLAY INVISIBLE (-6225 3375);
FORCEPROP 1 LAST PATH I10
J 0
(-6552 3500);
DISPLAY 0.872340 (-6552 3500);
PAINT GREEN (-6552 3500);
DISPLAY INVISIBLE (-6552 3500);
FORCEADD TAP..1
(-6550 3850);
FORCEPROP 3 LASTPIN (-6600 3850) SIG_NAME P5E_CPU1_P3_RX_BUF_DN<12>
J 0
(-6590 3860);
DISPLAY 0.659574 (-6590 3860);
PAINT MONO (-6590 3860);
DISPLAY INVISIBLE (-6590 3860);
FORCEPROP 1 LASTPIN (-6600 3850) BN 12
J 0
(-6612 3858);
DISPLAY 0.680851 (-6612 3858);
PAINT GREEN (-6612 3858);
FORCEPROP 2 LAST CDS_LIB standard
J 0
(-6550 3850);
DISPLAY INVISIBLE (-6550 3850);
FORCEPROP 1 LAST BODY_TYPE PLUMBING
J 0
(-6550 3900);
DISPLAY 0.872340 (-6550 3900);
PAINT GREEN (-6550 3900);
DISPLAY INVISIBLE (-6550 3900);
FORCEPROP 1 LAST HDL_TAP TRUE
J 0
(-6225 3725);
DISPLAY 0.872340 (-6225 3725);
DISPLAY INVISIBLE (-6225 3725);
FORCEPROP 1 LAST PATH I11
J 0
(-6552 3850);
DISPLAY 0.872340 (-6552 3850);
PAINT GREEN (-6552 3850);
DISPLAY INVISIBLE (-6552 3850);
FORCEADD TAP..1
(-6750 4300);
FORCEPROP 3 LASTPIN (-6800 4300) SIG_NAME P5E_CPU1_P3_RX_BUF_DP<13>
J 0
(-6790 4310);
DISPLAY 0.659574 (-6790 4310);
PAINT MONO (-6790 4310);
DISPLAY INVISIBLE (-6790 4310);
FORCEPROP 1 LASTPIN (-6800 4300) BN 13
J 0
(-6812 4308);
DISPLAY 0.680851 (-6812 4308);
PAINT GREEN (-6812 4308);
FORCEPROP 2 LAST CDS_LIB standard
J 0
(-6750 4300);
DISPLAY INVISIBLE (-6750 4300);
FORCEPROP 1 LAST BODY_TYPE PLUMBING
J 0
(-6750 4350);
DISPLAY 0.872340 (-6750 4350);
PAINT GREEN (-6750 4350);
DISPLAY INVISIBLE (-6750 4350);
FORCEPROP 1 LAST HDL_TAP TRUE
J 0
(-6425 4175);
DISPLAY 0.872340 (-6425 4175);
DISPLAY INVISIBLE (-6425 4175);
FORCEPROP 1 LAST PATH I12
J 0
(-6752 4300);
DISPLAY 0.872340 (-6752 4300);
PAINT GREEN (-6752 4300);
DISPLAY INVISIBLE (-6752 4300);
FORCEADD TAP..1
(-6750 4650);
FORCEPROP 3 LASTPIN (-6800 4650) SIG_NAME P5E_CPU1_P3_RX_BUF_DP<14>
J 0
(-6790 4660);
DISPLAY 0.659574 (-6790 4660);
PAINT MONO (-6790 4660);
DISPLAY INVISIBLE (-6790 4660);
FORCEPROP 1 LASTPIN (-6800 4650) BN 14
J 0
(-6812 4658);
DISPLAY 0.680851 (-6812 4658);
PAINT GREEN (-6812 4658);
FORCEPROP 2 LAST CDS_LIB standard
J 0
(-6750 4650);
DISPLAY INVISIBLE (-6750 4650);
FORCEPROP 1 LAST BODY_TYPE PLUMBING
J 0
(-6750 4700);
DISPLAY 0.872340 (-6750 4700);
PAINT GREEN (-6750 4700);
DISPLAY INVISIBLE (-6750 4700);
FORCEPROP 1 LAST HDL_TAP TRUE
J 0
(-6425 4525);
DISPLAY 0.872340 (-6425 4525);
DISPLAY INVISIBLE (-6425 4525);
FORCEPROP 1 LAST PATH I13
J 0
(-6752 4650);
DISPLAY 0.872340 (-6752 4650);
PAINT GREEN (-6752 4650);
DISPLAY INVISIBLE (-6752 4650);
FORCEADD TAP..1
(-6750 5000);
FORCEPROP 3 LASTPIN (-6800 5000) SIG_NAME P5E_CPU1_P3_RX_BUF_DP<15>
J 0
(-6790 5010);
DISPLAY 0.659574 (-6790 5010);
PAINT MONO (-6790 5010);
DISPLAY INVISIBLE (-6790 5010);
FORCEPROP 1 LASTPIN (-6800 5000) BN 15
J 0
(-6812 5008);
DISPLAY 0.680851 (-6812 5008);
PAINT GREEN (-6812 5008);
FORCEPROP 2 LAST CDS_LIB standard
J 0
(-6750 5000);
DISPLAY INVISIBLE (-6750 5000);
FORCEPROP 1 LAST BODY_TYPE PLUMBING
J 0
(-6750 5050);
DISPLAY 0.872340 (-6750 5050);
PAINT GREEN (-6750 5050);
DISPLAY INVISIBLE (-6750 5050);
FORCEPROP 1 LAST HDL_TAP TRUE
J 0
(-6425 4875);
DISPLAY 0.872340 (-6425 4875);
DISPLAY INVISIBLE (-6425 4875);
FORCEPROP 1 LAST PATH I14
J 0
(-6752 5000);
DISPLAY 0.872340 (-6752 5000);
PAINT GREEN (-6752 5000);
DISPLAY INVISIBLE (-6752 5000);
FORCEADD TAP..1
(-6550 4200);
FORCEPROP 3 LASTPIN (-6600 4200) SIG_NAME P5E_CPU1_P3_RX_BUF_DN<13>
J 0
(-6590 4210);
DISPLAY 0.659574 (-6590 4210);
PAINT MONO (-6590 4210);
DISPLAY INVISIBLE (-6590 4210);
FORCEPROP 1 LASTPIN (-6600 4200) BN 13
J 0
(-6612 4208);
DISPLAY 0.680851 (-6612 4208);
PAINT GREEN (-6612 4208);
FORCEPROP 2 LAST CDS_LIB standard
J 0
(-6550 4200);
DISPLAY INVISIBLE (-6550 4200);
FORCEPROP 1 LAST BODY_TYPE PLUMBING
J 0
(-6550 4250);
DISPLAY 0.872340 (-6550 4250);
PAINT GREEN (-6550 4250);
DISPLAY INVISIBLE (-6550 4250);
FORCEPROP 1 LAST HDL_TAP TRUE
J 0
(-6225 4075);
DISPLAY 0.872340 (-6225 4075);
DISPLAY INVISIBLE (-6225 4075);
FORCEPROP 1 LAST PATH I15
J 0
(-6552 4200);
DISPLAY 0.872340 (-6552 4200);
PAINT GREEN (-6552 4200);
DISPLAY INVISIBLE (-6552 4200);
FORCEADD TAP..1
(-6550 4550);
FORCEPROP 3 LASTPIN (-6600 4550) SIG_NAME P5E_CPU1_P3_RX_BUF_DN<14>
J 0
(-6590 4560);
DISPLAY 0.659574 (-6590 4560);
PAINT MONO (-6590 4560);
DISPLAY INVISIBLE (-6590 4560);
FORCEPROP 1 LASTPIN (-6600 4550) BN 14
J 0
(-6612 4558);
DISPLAY 0.680851 (-6612 4558);
PAINT GREEN (-6612 4558);
FORCEPROP 2 LAST CDS_LIB standard
J 0
(-6550 4550);
DISPLAY INVISIBLE (-6550 4550);
FORCEPROP 1 LAST BODY_TYPE PLUMBING
J 0
(-6550 4600);
DISPLAY 0.872340 (-6550 4600);
PAINT GREEN (-6550 4600);
DISPLAY INVISIBLE (-6550 4600);
FORCEPROP 1 LAST HDL_TAP TRUE
J 0
(-6225 4425);
DISPLAY 0.872340 (-6225 4425);
DISPLAY INVISIBLE (-6225 4425);
FORCEPROP 1 LAST PATH I16
J 0
(-6552 4550);
DISPLAY 0.872340 (-6552 4550);
PAINT GREEN (-6552 4550);
DISPLAY INVISIBLE (-6552 4550);
FORCEADD TAP..1
(-6550 4900);
FORCEPROP 3 LASTPIN (-6600 4900) SIG_NAME P5E_CPU1_P3_RX_BUF_DN<15>
J 0
(-6590 4910);
DISPLAY 0.659574 (-6590 4910);
PAINT MONO (-6590 4910);
DISPLAY INVISIBLE (-6590 4910);
FORCEPROP 1 LASTPIN (-6600 4900) BN 15
J 0
(-6612 4908);
DISPLAY 0.680851 (-6612 4908);
PAINT GREEN (-6612 4908);
FORCEPROP 2 LAST CDS_LIB standard
J 0
(-6550 4900);
DISPLAY INVISIBLE (-6550 4900);
FORCEPROP 1 LAST BODY_TYPE PLUMBING
J 0
(-6550 4950);
DISPLAY 0.872340 (-6550 4950);
PAINT GREEN (-6550 4950);
DISPLAY INVISIBLE (-6550 4950);
FORCEPROP 1 LAST HDL_TAP TRUE
J 0
(-6225 4775);
DISPLAY 0.872340 (-6225 4775);
DISPLAY INVISIBLE (-6225 4775);
FORCEPROP 1 LAST PATH I17
J 0
(-6552 4900);
DISPLAY 0.872340 (-6552 4900);
PAINT GREEN (-6552 4900);
DISPLAY INVISIBLE (-6552 4900);
FORCEADD OFFPAGE..1
R 2
(-5525 5025);
FORCEPROP 2 LAST $XR0 119 
J 0
(-5339 5025);
DISPLAY 0.638298 (-5339 5025);
PAINT MONO (-5339 5025);
FORCEPROP 2 LAST CDS_LIB standard
J 0
(-5525 5025);
DISPLAY INVISIBLE (-5525 5025);
FORCEPROP 1 LAST OFFPAGE TRUE
J 2
(-5850 4900);
DISPLAY 0.872340 (-5850 4900);
DISPLAY INVISIBLE (-5850 4900);
FORCEPROP 1 LAST COMMENT_BODY TRUE
J 2
(-5650 4925);
DISPLAY 0.872340 (-5650 4925);
PAINT GREEN (-5650 4925);
DISPLAY INVISIBLE (-5650 4925);
FORCEPROP 2 LAST PATH I18
J 0
(-5350 5100);
DISPLAY 0.680851 (-5350 5100);
DISPLAY INVISIBLE (-5350 5100);
FORCEADD OFFPAGE..1
R 2
(-5525 5100);
FORCEPROP 2 LAST $XR0 119 
J 0
(-5339 5100);
DISPLAY 0.638298 (-5339 5100);
PAINT MONO (-5339 5100);
FORCEPROP 2 LAST CDS_LIB standard
J 0
(-5525 5100);
DISPLAY INVISIBLE (-5525 5100);
FORCEPROP 1 LAST OFFPAGE TRUE
J 2
(-5850 4975);
DISPLAY 0.872340 (-5850 4975);
DISPLAY INVISIBLE (-5850 4975);
FORCEPROP 1 LAST COMMENT_BODY TRUE
J 2
(-5650 5000);
DISPLAY 0.872340 (-5650 5000);
PAINT GREEN (-5650 5000);
DISPLAY INVISIBLE (-5650 5000);
FORCEPROP 2 LAST PATH I19
J 0
(-5350 5175);
DISPLAY 0.680851 (-5350 5175);
DISPLAY INVISIBLE (-5350 5175);
FORCEADD TAP..1
(-6750 2550);
FORCEPROP 3 LASTPIN (-6800 2550) SIG_NAME P5E_CPU1_P3_RX_BUF_DP<8>
J 0
(-6790 2560);
DISPLAY 0.659574 (-6790 2560);
PAINT MONO (-6790 2560);
DISPLAY INVISIBLE (-6790 2560);
FORCEPROP 1 LASTPIN (-6800 2550) BN 8
J 0
(-6812 2558);
DISPLAY 0.680851 (-6812 2558);
PAINT GREEN (-6812 2558);
FORCEPROP 2 LAST CDS_LIB standard
J 0
(-6750 2550);
DISPLAY INVISIBLE (-6750 2550);
FORCEPROP 1 LAST BODY_TYPE PLUMBING
J 0
(-6750 2600);
DISPLAY 0.872340 (-6750 2600);
PAINT GREEN (-6750 2600);
DISPLAY INVISIBLE (-6750 2600);
FORCEPROP 1 LAST HDL_TAP TRUE
J 0
(-6425 2425);
DISPLAY 0.872340 (-6425 2425);
DISPLAY INVISIBLE (-6425 2425);
FORCEPROP 1 LAST PATH I2
J 0
(-6752 2550);
DISPLAY 0.872340 (-6752 2550);
PAINT GREEN (-6752 2550);
DISPLAY INVISIBLE (-6752 2550);
FORCEADD TAP..1
(-2300 2575);
FORCEPROP 3 LASTPIN (-2350 2575) SIG_NAME P5E_CPU1_P3_RX_BUF_DP<0>
J 0
(-2340 2585);
DISPLAY 0.659574 (-2340 2585);
PAINT MONO (-2340 2585);
DISPLAY INVISIBLE (-2340 2585);
FORCEPROP 1 LASTPIN (-2350 2575) BN 0
J 0
(-2362 2583);
DISPLAY 0.680851 (-2362 2583);
PAINT GREEN (-2362 2583);
FORCEPROP 2 LAST CDS_LIB standard
J 0
(-2300 2575);
DISPLAY INVISIBLE (-2300 2575);
FORCEPROP 1 LAST BODY_TYPE PLUMBING
J 0
(-2300 2625);
DISPLAY 0.872340 (-2300 2625);
PAINT GREEN (-2300 2625);
DISPLAY INVISIBLE (-2300 2625);
FORCEPROP 1 LAST HDL_TAP TRUE
J 0
(-1975 2450);
DISPLAY 0.872340 (-1975 2450);
DISPLAY INVISIBLE (-1975 2450);
FORCEPROP 1 LAST PATH I20
J 0
(-2302 2575);
DISPLAY 0.872340 (-2302 2575);
PAINT GREEN (-2302 2575);
DISPLAY INVISIBLE (-2302 2575);
FORCEADD TAP..1
(-2300 2925);
FORCEPROP 3 LASTPIN (-2350 2925) SIG_NAME P5E_CPU1_P3_RX_BUF_DP<1>
J 0
(-2340 2935);
DISPLAY 0.659574 (-2340 2935);
PAINT MONO (-2340 2935);
DISPLAY INVISIBLE (-2340 2935);
FORCEPROP 1 LASTPIN (-2350 2925) BN 1
J 0
(-2362 2933);
DISPLAY 0.680851 (-2362 2933);
PAINT GREEN (-2362 2933);
FORCEPROP 2 LAST CDS_LIB standard
J 0
(-2300 2925);
DISPLAY INVISIBLE (-2300 2925);
FORCEPROP 1 LAST BODY_TYPE PLUMBING
J 0
(-2300 2975);
DISPLAY 0.872340 (-2300 2975);
PAINT GREEN (-2300 2975);
DISPLAY INVISIBLE (-2300 2975);
FORCEPROP 1 LAST HDL_TAP TRUE
J 0
(-1975 2800);
DISPLAY 0.872340 (-1975 2800);
DISPLAY INVISIBLE (-1975 2800);
FORCEPROP 1 LAST PATH I21
J 0
(-2302 2925);
DISPLAY 0.872340 (-2302 2925);
PAINT GREEN (-2302 2925);
DISPLAY INVISIBLE (-2302 2925);
FORCEADD TAP..1
(-2100 2475);
FORCEPROP 3 LASTPIN (-2150 2475) SIG_NAME P5E_CPU1_P3_RX_BUF_DN<0>
J 0
(-2140 2485);
DISPLAY 0.659574 (-2140 2485);
PAINT MONO (-2140 2485);
DISPLAY INVISIBLE (-2140 2485);
FORCEPROP 1 LASTPIN (-2150 2475) BN 0
J 0
(-2162 2483);
DISPLAY 0.680851 (-2162 2483);
PAINT GREEN (-2162 2483);
FORCEPROP 2 LAST CDS_LIB standard
J 0
(-2100 2475);
DISPLAY INVISIBLE (-2100 2475);
FORCEPROP 1 LAST BODY_TYPE PLUMBING
J 0
(-2100 2525);
DISPLAY 0.872340 (-2100 2525);
PAINT GREEN (-2100 2525);
DISPLAY INVISIBLE (-2100 2525);
FORCEPROP 1 LAST HDL_TAP TRUE
J 0
(-1775 2350);
DISPLAY 0.872340 (-1775 2350);
DISPLAY INVISIBLE (-1775 2350);
FORCEPROP 1 LAST PATH I22
J 0
(-2102 2475);
DISPLAY 0.872340 (-2102 2475);
PAINT GREEN (-2102 2475);
DISPLAY INVISIBLE (-2102 2475);
FORCEADD TAP..1
(-2100 2825);
FORCEPROP 3 LASTPIN (-2150 2825) SIG_NAME P5E_CPU1_P3_RX_BUF_DN<1>
J 0
(-2140 2835);
DISPLAY 0.659574 (-2140 2835);
PAINT MONO (-2140 2835);
DISPLAY INVISIBLE (-2140 2835);
FORCEPROP 1 LASTPIN (-2150 2825) BN 1
J 0
(-2162 2833);
DISPLAY 0.680851 (-2162 2833);
PAINT GREEN (-2162 2833);
FORCEPROP 2 LAST CDS_LIB standard
J 0
(-2100 2825);
DISPLAY INVISIBLE (-2100 2825);
FORCEPROP 1 LAST BODY_TYPE PLUMBING
J 0
(-2100 2875);
DISPLAY 0.872340 (-2100 2875);
PAINT GREEN (-2100 2875);
DISPLAY INVISIBLE (-2100 2875);
FORCEPROP 1 LAST HDL_TAP TRUE
J 0
(-1775 2700);
DISPLAY 0.872340 (-1775 2700);
DISPLAY INVISIBLE (-1775 2700);
FORCEPROP 1 LAST PATH I23
J 0
(-2102 2825);
DISPLAY 0.872340 (-2102 2825);
PAINT GREEN (-2102 2825);
DISPLAY INVISIBLE (-2102 2825);
FORCEADD TAP..1
(-2300 3275);
FORCEPROP 3 LASTPIN (-2350 3275) SIG_NAME P5E_CPU1_P3_RX_BUF_DP<2>
J 0
(-2340 3285);
DISPLAY 0.659574 (-2340 3285);
PAINT MONO (-2340 3285);
DISPLAY INVISIBLE (-2340 3285);
FORCEPROP 1 LASTPIN (-2350 3275) BN 2
J 0
(-2362 3283);
DISPLAY 0.680851 (-2362 3283);
PAINT GREEN (-2362 3283);
FORCEPROP 2 LAST CDS_LIB standard
J 0
(-2300 3275);
DISPLAY INVISIBLE (-2300 3275);
FORCEPROP 1 LAST BODY_TYPE PLUMBING
J 0
(-2300 3325);
DISPLAY 0.872340 (-2300 3325);
PAINT GREEN (-2300 3325);
DISPLAY INVISIBLE (-2300 3325);
FORCEPROP 1 LAST HDL_TAP TRUE
J 0
(-1975 3150);
DISPLAY 0.872340 (-1975 3150);
DISPLAY INVISIBLE (-1975 3150);
FORCEPROP 1 LAST PATH I24
J 0
(-2302 3275);
DISPLAY 0.872340 (-2302 3275);
PAINT GREEN (-2302 3275);
DISPLAY INVISIBLE (-2302 3275);
FORCEADD TAP..1
(-2100 3175);
FORCEPROP 3 LASTPIN (-2150 3175) SIG_NAME P5E_CPU1_P3_RX_BUF_DN<2>
J 0
(-2140 3185);
DISPLAY 0.659574 (-2140 3185);
PAINT MONO (-2140 3185);
DISPLAY INVISIBLE (-2140 3185);
FORCEPROP 1 LASTPIN (-2150 3175) BN 2
J 0
(-2162 3183);
DISPLAY 0.680851 (-2162 3183);
PAINT GREEN (-2162 3183);
FORCEPROP 2 LAST CDS_LIB standard
J 0
(-2100 3175);
DISPLAY INVISIBLE (-2100 3175);
FORCEPROP 1 LAST BODY_TYPE PLUMBING
J 0
(-2100 3225);
DISPLAY 0.872340 (-2100 3225);
PAINT GREEN (-2100 3225);
DISPLAY INVISIBLE (-2100 3225);
FORCEPROP 1 LAST HDL_TAP TRUE
J 0
(-1775 3050);
DISPLAY 0.872340 (-1775 3050);
DISPLAY INVISIBLE (-1775 3050);
FORCEPROP 1 LAST PATH I25
J 0
(-2102 3175);
DISPLAY 0.872340 (-2102 3175);
PAINT GREEN (-2102 3175);
DISPLAY INVISIBLE (-2102 3175);
FORCEADD TAP..1
(-2300 3625);
FORCEPROP 3 LASTPIN (-2350 3625) SIG_NAME P5E_CPU1_P3_RX_BUF_DP<3>
J 0
(-2340 3635);
DISPLAY 0.659574 (-2340 3635);
PAINT MONO (-2340 3635);
DISPLAY INVISIBLE (-2340 3635);
FORCEPROP 1 LASTPIN (-2350 3625) BN 3
J 0
(-2362 3633);
DISPLAY 0.680851 (-2362 3633);
PAINT GREEN (-2362 3633);
FORCEPROP 2 LAST CDS_LIB standard
J 0
(-2300 3625);
DISPLAY INVISIBLE (-2300 3625);
FORCEPROP 1 LAST BODY_TYPE PLUMBING
J 0
(-2300 3675);
DISPLAY 0.872340 (-2300 3675);
PAINT GREEN (-2300 3675);
DISPLAY INVISIBLE (-2300 3675);
FORCEPROP 1 LAST HDL_TAP TRUE
J 0
(-1975 3500);
DISPLAY 0.872340 (-1975 3500);
DISPLAY INVISIBLE (-1975 3500);
FORCEPROP 1 LAST PATH I26
J 0
(-2302 3625);
DISPLAY 0.872340 (-2302 3625);
PAINT GREEN (-2302 3625);
DISPLAY INVISIBLE (-2302 3625);
FORCEADD TAP..1
(-2300 3975);
FORCEPROP 3 LASTPIN (-2350 3975) SIG_NAME P5E_CPU1_P3_RX_BUF_DP<4>
J 0
(-2340 3985);
DISPLAY 0.659574 (-2340 3985);
PAINT MONO (-2340 3985);
DISPLAY INVISIBLE (-2340 3985);
FORCEPROP 1 LASTPIN (-2350 3975) BN 4
J 0
(-2362 3983);
DISPLAY 0.680851 (-2362 3983);
PAINT GREEN (-2362 3983);
FORCEPROP 2 LAST CDS_LIB standard
J 0
(-2300 3975);
DISPLAY INVISIBLE (-2300 3975);
FORCEPROP 1 LAST BODY_TYPE PLUMBING
J 0
(-2300 4025);
DISPLAY 0.872340 (-2300 4025);
PAINT GREEN (-2300 4025);
DISPLAY INVISIBLE (-2300 4025);
FORCEPROP 1 LAST HDL_TAP TRUE
J 0
(-1975 3850);
DISPLAY 0.872340 (-1975 3850);
DISPLAY INVISIBLE (-1975 3850);
FORCEPROP 1 LAST PATH I27
J 0
(-2302 3975);
DISPLAY 0.872340 (-2302 3975);
PAINT GREEN (-2302 3975);
DISPLAY INVISIBLE (-2302 3975);
FORCEADD TAP..1
(-2100 3525);
FORCEPROP 3 LASTPIN (-2150 3525) SIG_NAME P5E_CPU1_P3_RX_BUF_DN<3>
J 0
(-2140 3535);
DISPLAY 0.659574 (-2140 3535);
PAINT MONO (-2140 3535);
DISPLAY INVISIBLE (-2140 3535);
FORCEPROP 1 LASTPIN (-2150 3525) BN 3
J 0
(-2162 3533);
DISPLAY 0.680851 (-2162 3533);
PAINT GREEN (-2162 3533);
FORCEPROP 2 LAST CDS_LIB standard
J 0
(-2100 3525);
DISPLAY INVISIBLE (-2100 3525);
FORCEPROP 1 LAST BODY_TYPE PLUMBING
J 0
(-2100 3575);
DISPLAY 0.872340 (-2100 3575);
PAINT GREEN (-2100 3575);
DISPLAY INVISIBLE (-2100 3575);
FORCEPROP 1 LAST HDL_TAP TRUE
J 0
(-1775 3400);
DISPLAY 0.872340 (-1775 3400);
DISPLAY INVISIBLE (-1775 3400);
FORCEPROP 1 LAST PATH I28
J 0
(-2102 3525);
DISPLAY 0.872340 (-2102 3525);
PAINT GREEN (-2102 3525);
DISPLAY INVISIBLE (-2102 3525);
FORCEADD TAP..1
(-2100 3875);
FORCEPROP 3 LASTPIN (-2150 3875) SIG_NAME P5E_CPU1_P3_RX_BUF_DN<4>
J 0
(-2140 3885);
DISPLAY 0.659574 (-2140 3885);
PAINT MONO (-2140 3885);
DISPLAY INVISIBLE (-2140 3885);
FORCEPROP 1 LASTPIN (-2150 3875) BN 4
J 0
(-2162 3883);
DISPLAY 0.680851 (-2162 3883);
PAINT GREEN (-2162 3883);
FORCEPROP 2 LAST CDS_LIB standard
J 0
(-2100 3875);
DISPLAY INVISIBLE (-2100 3875);
FORCEPROP 1 LAST BODY_TYPE PLUMBING
J 0
(-2100 3925);
DISPLAY 0.872340 (-2100 3925);
PAINT GREEN (-2100 3925);
DISPLAY INVISIBLE (-2100 3925);
FORCEPROP 1 LAST HDL_TAP TRUE
J 0
(-1775 3750);
DISPLAY 0.872340 (-1775 3750);
DISPLAY INVISIBLE (-1775 3750);
FORCEPROP 1 LAST PATH I29
J 0
(-2102 3875);
DISPLAY 0.872340 (-2102 3875);
PAINT GREEN (-2102 3875);
DISPLAY INVISIBLE (-2102 3875);
FORCEADD TAP..1
(-6750 2900);
FORCEPROP 3 LASTPIN (-6800 2900) SIG_NAME P5E_CPU1_P3_RX_BUF_DP<9>
J 0
(-6790 2910);
DISPLAY 0.659574 (-6790 2910);
PAINT MONO (-6790 2910);
DISPLAY INVISIBLE (-6790 2910);
FORCEPROP 1 LASTPIN (-6800 2900) BN 9
J 0
(-6812 2908);
DISPLAY 0.680851 (-6812 2908);
PAINT GREEN (-6812 2908);
FORCEPROP 2 LAST CDS_LIB standard
J 0
(-6750 2900);
DISPLAY INVISIBLE (-6750 2900);
FORCEPROP 1 LAST BODY_TYPE PLUMBING
J 0
(-6750 2950);
DISPLAY 0.872340 (-6750 2950);
PAINT GREEN (-6750 2950);
DISPLAY INVISIBLE (-6750 2950);
FORCEPROP 1 LAST HDL_TAP TRUE
J 0
(-6425 2775);
DISPLAY 0.872340 (-6425 2775);
DISPLAY INVISIBLE (-6425 2775);
FORCEPROP 1 LAST PATH I3
J 0
(-6752 2900);
DISPLAY 0.872340 (-6752 2900);
PAINT GREEN (-6752 2900);
DISPLAY INVISIBLE (-6752 2900);
FORCEADD TAP..1
(-2300 4325);
FORCEPROP 3 LASTPIN (-2350 4325) SIG_NAME P5E_CPU1_P3_RX_BUF_DP<5>
J 0
(-2340 4335);
DISPLAY 0.659574 (-2340 4335);
PAINT MONO (-2340 4335);
DISPLAY INVISIBLE (-2340 4335);
FORCEPROP 1 LASTPIN (-2350 4325) BN 5
J 0
(-2362 4333);
DISPLAY 0.680851 (-2362 4333);
PAINT GREEN (-2362 4333);
FORCEPROP 2 LAST CDS_LIB standard
J 0
(-2300 4325);
DISPLAY INVISIBLE (-2300 4325);
FORCEPROP 1 LAST BODY_TYPE PLUMBING
J 0
(-2300 4375);
DISPLAY 0.872340 (-2300 4375);
PAINT GREEN (-2300 4375);
DISPLAY INVISIBLE (-2300 4375);
FORCEPROP 1 LAST HDL_TAP TRUE
J 0
(-1975 4200);
DISPLAY 0.872340 (-1975 4200);
DISPLAY INVISIBLE (-1975 4200);
FORCEPROP 1 LAST PATH I30
J 0
(-2302 4325);
DISPLAY 0.872340 (-2302 4325);
PAINT GREEN (-2302 4325);
DISPLAY INVISIBLE (-2302 4325);
FORCEADD TAP..1
(-2100 4225);
FORCEPROP 3 LASTPIN (-2150 4225) SIG_NAME P5E_CPU1_P3_RX_BUF_DN<5>
J 0
(-2140 4235);
DISPLAY 0.659574 (-2140 4235);
PAINT MONO (-2140 4235);
DISPLAY INVISIBLE (-2140 4235);
FORCEPROP 1 LASTPIN (-2150 4225) BN 5
J 0
(-2162 4233);
DISPLAY 0.680851 (-2162 4233);
PAINT GREEN (-2162 4233);
FORCEPROP 2 LAST CDS_LIB standard
J 0
(-2100 4225);
DISPLAY INVISIBLE (-2100 4225);
FORCEPROP 1 LAST BODY_TYPE PLUMBING
J 0
(-2100 4275);
DISPLAY 0.872340 (-2100 4275);
PAINT GREEN (-2100 4275);
DISPLAY INVISIBLE (-2100 4275);
FORCEPROP 1 LAST HDL_TAP TRUE
J 0
(-1775 4100);
DISPLAY 0.872340 (-1775 4100);
DISPLAY INVISIBLE (-1775 4100);
FORCEPROP 1 LAST PATH I31
J 0
(-2102 4225);
DISPLAY 0.872340 (-2102 4225);
PAINT GREEN (-2102 4225);
DISPLAY INVISIBLE (-2102 4225);
FORCEADD TAP..1
(-2300 4675);
FORCEPROP 3 LASTPIN (-2350 4675) SIG_NAME P5E_CPU1_P3_RX_BUF_DP<6>
J 0
(-2340 4685);
DISPLAY 0.659574 (-2340 4685);
PAINT MONO (-2340 4685);
DISPLAY INVISIBLE (-2340 4685);
FORCEPROP 1 LASTPIN (-2350 4675) BN 6
J 0
(-2362 4683);
DISPLAY 0.680851 (-2362 4683);
PAINT GREEN (-2362 4683);
FORCEPROP 2 LAST CDS_LIB standard
J 0
(-2300 4675);
DISPLAY INVISIBLE (-2300 4675);
FORCEPROP 1 LAST BODY_TYPE PLUMBING
J 0
(-2300 4725);
DISPLAY 0.872340 (-2300 4725);
PAINT GREEN (-2300 4725);
DISPLAY INVISIBLE (-2300 4725);
FORCEPROP 1 LAST HDL_TAP TRUE
J 0
(-1975 4550);
DISPLAY 0.872340 (-1975 4550);
DISPLAY INVISIBLE (-1975 4550);
FORCEPROP 1 LAST PATH I32
J 0
(-2302 4675);
DISPLAY 0.872340 (-2302 4675);
PAINT GREEN (-2302 4675);
DISPLAY INVISIBLE (-2302 4675);
FORCEADD TAP..1
(-2100 4575);
FORCEPROP 3 LASTPIN (-2150 4575) SIG_NAME P5E_CPU1_P3_RX_BUF_DN<6>
J 0
(-2140 4585);
DISPLAY 0.659574 (-2140 4585);
PAINT MONO (-2140 4585);
DISPLAY INVISIBLE (-2140 4585);
FORCEPROP 1 LASTPIN (-2150 4575) BN 6
J 0
(-2162 4583);
DISPLAY 0.680851 (-2162 4583);
PAINT GREEN (-2162 4583);
FORCEPROP 2 LAST CDS_LIB standard
J 0
(-2100 4575);
DISPLAY INVISIBLE (-2100 4575);
FORCEPROP 1 LAST BODY_TYPE PLUMBING
J 0
(-2100 4625);
DISPLAY 0.872340 (-2100 4625);
PAINT GREEN (-2100 4625);
DISPLAY INVISIBLE (-2100 4625);
FORCEPROP 1 LAST HDL_TAP TRUE
J 0
(-1775 4450);
DISPLAY 0.872340 (-1775 4450);
DISPLAY INVISIBLE (-1775 4450);
FORCEPROP 1 LAST PATH I33
J 0
(-2102 4575);
DISPLAY 0.872340 (-2102 4575);
PAINT GREEN (-2102 4575);
DISPLAY INVISIBLE (-2102 4575);
FORCEADD TAP..1
(-2100 4925);
FORCEPROP 3 LASTPIN (-2150 4925) SIG_NAME P5E_CPU1_P3_RX_BUF_DN<7>
J 0
(-2140 4935);
DISPLAY 0.659574 (-2140 4935);
PAINT MONO (-2140 4935);
DISPLAY INVISIBLE (-2140 4935);
FORCEPROP 1 LASTPIN (-2150 4925) BN 7
J 0
(-2162 4933);
DISPLAY 0.680851 (-2162 4933);
PAINT GREEN (-2162 4933);
FORCEPROP 2 LAST CDS_LIB standard
J 0
(-2100 4925);
DISPLAY INVISIBLE (-2100 4925);
FORCEPROP 1 LAST BODY_TYPE PLUMBING
J 0
(-2100 4975);
DISPLAY 0.872340 (-2100 4975);
PAINT GREEN (-2100 4975);
DISPLAY INVISIBLE (-2100 4975);
FORCEPROP 1 LAST HDL_TAP TRUE
J 0
(-1775 4800);
DISPLAY 0.872340 (-1775 4800);
DISPLAY INVISIBLE (-1775 4800);
FORCEPROP 1 LAST PATH I34
J 0
(-2102 4925);
DISPLAY 0.872340 (-2102 4925);
PAINT GREEN (-2102 4925);
DISPLAY INVISIBLE (-2102 4925);
FORCEADD TAP..1
(-2300 5025);
FORCEPROP 3 LASTPIN (-2350 5025) SIG_NAME P5E_CPU1_P3_RX_BUF_DP<7>
J 0
(-2340 5035);
DISPLAY 0.659574 (-2340 5035);
PAINT MONO (-2340 5035);
DISPLAY INVISIBLE (-2340 5035);
FORCEPROP 1 LASTPIN (-2350 5025) BN 7
J 0
(-2362 5033);
DISPLAY 0.680851 (-2362 5033);
PAINT GREEN (-2362 5033);
FORCEPROP 2 LAST CDS_LIB standard
J 0
(-2300 5025);
DISPLAY INVISIBLE (-2300 5025);
FORCEPROP 1 LAST BODY_TYPE PLUMBING
J 0
(-2300 5075);
DISPLAY 0.872340 (-2300 5075);
PAINT GREEN (-2300 5075);
DISPLAY INVISIBLE (-2300 5075);
FORCEPROP 1 LAST HDL_TAP TRUE
J 0
(-1975 4900);
DISPLAY 0.872340 (-1975 4900);
DISPLAY INVISIBLE (-1975 4900);
FORCEPROP 1 LAST PATH I35
J 0
(-2302 5025);
DISPLAY 0.872340 (-2302 5025);
PAINT GREEN (-2302 5025);
DISPLAY INVISIBLE (-2302 5025);
FORCEADD OFFPAGE..1
R 2
(-1075 5050);
FORCEPROP 2 LAST $XR0 120 
J 0
(-889 5050);
DISPLAY 0.638298 (-889 5050);
PAINT MONO (-889 5050);
FORCEPROP 2 LAST CDS_LIB standard
J 0
(-1075 5050);
DISPLAY INVISIBLE (-1075 5050);
FORCEPROP 1 LAST OFFPAGE TRUE
J 2
(-1400 4925);
DISPLAY 0.872340 (-1400 4925);
DISPLAY INVISIBLE (-1400 4925);
FORCEPROP 1 LAST COMMENT_BODY TRUE
J 2
(-1200 4950);
DISPLAY 0.872340 (-1200 4950);
PAINT GREEN (-1200 4950);
DISPLAY INVISIBLE (-1200 4950);
FORCEPROP 2 LAST PATH I36
J 0
(-900 5125);
DISPLAY 0.680851 (-900 5125);
DISPLAY INVISIBLE (-900 5125);
FORCEADD OFFPAGE..1
R 2
(-1075 5125);
FORCEPROP 2 LAST $XR0 120 
J 0
(-889 5125);
DISPLAY 0.638298 (-889 5125);
PAINT MONO (-889 5125);
FORCEPROP 2 LAST CDS_LIB standard
J 0
(-1075 5125);
DISPLAY INVISIBLE (-1075 5125);
FORCEPROP 1 LAST OFFPAGE TRUE
J 2
(-1400 5000);
DISPLAY 0.872340 (-1400 5000);
DISPLAY INVISIBLE (-1400 5000);
FORCEPROP 1 LAST COMMENT_BODY TRUE
J 2
(-1200 5025);
DISPLAY 0.872340 (-1200 5025);
PAINT GREEN (-1200 5025);
DISPLAY INVISIBLE (-1200 5025);
FORCEPROP 2 LAST PATH I37
J 0
(-900 5200);
DISPLAY 0.680851 (-900 5200);
DISPLAY INVISIBLE (-900 5200);
FORCEADD PT5161LRS..2
(-3325 3775);
FORCEPROP 1 LAST LOCATION U6017
J 0
(-3675 5400);
DISPLAY 0.723404 (-3675 5400);
PAINT GREEN (-3675 5400);
FORCEPROP 0 LAST $SEC 2
J 0
(-3675 5550);
DISPLAY 0.680851 (-3675 5550);
PAINT MONO (-3675 5550);
DISPLAY INVISIBLE (-3675 5550);
FORCEPROP 0 LAST CDS_SEC 2
J 0
(-3675 5550);
DISPLAY 0.680851 (-3675 5550);
DISPLAY INVISIBLE (-3675 5550);
FORCEPROP 0 LASTPIN (-2875 4925) $PN CJ2
J 0
(-2865 4935);
DISPLAY 0.680851 (-2865 4935);
PAINT MONO (-2865 4935);
FORCEPROP 0 LASTPIN (-2875 4575) $PN CT2
J 0
(-2865 4585);
DISPLAY 0.680851 (-2865 4585);
PAINT MONO (-2865 4585);
FORCEPROP 0 LASTPIN (-2875 4225) $PN DC2
J 0
(-2865 4235);
DISPLAY 0.680851 (-2865 4235);
PAINT MONO (-2865 4235);
FORCEPROP 0 LASTPIN (-2875 3875) $PN DK2
J 0
(-2865 3885);
DISPLAY 0.680851 (-2865 3885);
PAINT MONO (-2865 3885);
FORCEPROP 0 LASTPIN (-2875 3525) $PN DU2
J 0
(-2865 3535);
DISPLAY 0.680851 (-2865 3535);
PAINT MONO (-2865 3535);
FORCEPROP 0 LASTPIN (-2875 3175) $PN ED2
J 0
(-2865 3185);
DISPLAY 0.680851 (-2865 3185);
PAINT MONO (-2865 3185);
FORCEPROP 0 LASTPIN (-2875 2825) $PN EL2
J 0
(-2865 2835);
DISPLAY 0.680851 (-2865 2835);
PAINT MONO (-2865 2835);
FORCEPROP 0 LASTPIN (-2875 2475) $PN EV2
J 0
(-2865 2485);
DISPLAY 0.680851 (-2865 2485);
PAINT MONO (-2865 2485);
FORCEPROP 0 LASTPIN (-2875 5025) $PN CL1
J 0
(-2865 5035);
DISPLAY 0.680851 (-2865 5035);
PAINT MONO (-2865 5035);
FORCEPROP 0 LASTPIN (-2875 4675) $PN CV1
J 0
(-2865 4685);
DISPLAY 0.680851 (-2865 4685);
PAINT MONO (-2865 4685);
FORCEPROP 0 LASTPIN (-2875 4325) $PN DE1
J 0
(-2865 4335);
DISPLAY 0.680851 (-2865 4335);
PAINT MONO (-2865 4335);
FORCEPROP 0 LASTPIN (-2875 3975) $PN DM1
J 0
(-2865 3985);
DISPLAY 0.680851 (-2865 3985);
PAINT MONO (-2865 3985);
FORCEPROP 0 LASTPIN (-2875 3625) $PN DW1
J 0
(-2865 3635);
DISPLAY 0.680851 (-2865 3635);
PAINT MONO (-2865 3635);
FORCEPROP 0 LASTPIN (-2875 3275) $PN EF1
J 0
(-2865 3285);
DISPLAY 0.680851 (-2865 3285);
PAINT MONO (-2865 3285);
FORCEPROP 0 LASTPIN (-2875 2925) $PN EN1
J 0
(-2865 2935);
DISPLAY 0.680851 (-2865 2935);
PAINT MONO (-2865 2935);
FORCEPROP 0 LASTPIN (-2875 2575) $PN EY1
J 0
(-2865 2585);
DISPLAY 0.680851 (-2865 2585);
PAINT MONO (-2865 2585);
FORCEPROP 2 LAST PART_TYPE SMLF
J 0
(-3675 5500);
DISPLAY 0.680851 (-3675 5500);
FORCEPROP 2 LAST VALUE PT5161LRS
J 0
(-3675 5450);
DISPLAY 0.680851 (-3675 5450);
FORCEPROP 1 LAST MATERIAL IC
J 0
(-3675 5250);
DISPLAY 0.723404 (-3675 5250);
PAINT GREEN (-3675 5250);
FORCEPROP 2 LAST CDS_LIB pure_quanta
J 0
(-3325 3775);
DISPLAY INVISIBLE (-3325 3775);
FORCEPROP 1 LAST CDS_LMAN_SYM_OUTLINE -350,1450,300,-1400
J 0
(-3325 3775);
DISPLAY 0.468085 (-3325 3775);
PAINT GREEN (-3325 3775);
DISPLAY INVISIBLE (-3325 3775);
FORCEPROP 1 LAST NEEDS_NO_SIZE TRUE
J 0
(-3325 3775);
DISPLAY 0.723404 (-3325 3775);
PAINT GREEN (-3325 3775);
DISPLAY INVISIBLE (-3325 3775);
FORCEPROP 1 LAST PATH I38
J 0
(-3325 3775);
DISPLAY 0.723404 (-3325 3775);
PAINT GREEN (-3325 3775);
DISPLAY INVISIBLE (-3325 3775);
FORCEPROP 1 LAST PART_NUMBER AJ051610U03
J 0
(-3675 5325);
DISPLAY 0.723404 (-3675 5325);
PAINT GREEN (-3675 5325);
DISPLAY INVISIBLE (-3675 5325);
FORCEADD TAP..1
(-6550 2450);
FORCEPROP 3 LASTPIN (-6600 2450) SIG_NAME P5E_CPU1_P3_RX_BUF_DN<8>
J 0
(-6590 2460);
DISPLAY 0.659574 (-6590 2460);
PAINT MONO (-6590 2460);
DISPLAY INVISIBLE (-6590 2460);
FORCEPROP 1 LASTPIN (-6600 2450) BN 8
J 0
(-6612 2458);
DISPLAY 0.680851 (-6612 2458);
PAINT GREEN (-6612 2458);
FORCEPROP 2 LAST CDS_LIB standard
J 0
(-6550 2450);
DISPLAY INVISIBLE (-6550 2450);
FORCEPROP 1 LAST BODY_TYPE PLUMBING
J 0
(-6550 2500);
DISPLAY 0.872340 (-6550 2500);
PAINT GREEN (-6550 2500);
DISPLAY INVISIBLE (-6550 2500);
FORCEPROP 1 LAST HDL_TAP TRUE
J 0
(-6225 2325);
DISPLAY 0.872340 (-6225 2325);
DISPLAY INVISIBLE (-6225 2325);
FORCEPROP 1 LAST PATH I4
J 0
(-6552 2450);
DISPLAY 0.872340 (-6552 2450);
PAINT GREEN (-6552 2450);
DISPLAY INVISIBLE (-6552 2450);
FORCEADD TAP..1
(-6550 2800);
FORCEPROP 3 LASTPIN (-6600 2800) SIG_NAME P5E_CPU1_P3_RX_BUF_DN<9>
J 0
(-6590 2810);
DISPLAY 0.659574 (-6590 2810);
PAINT MONO (-6590 2810);
DISPLAY INVISIBLE (-6590 2810);
FORCEPROP 1 LASTPIN (-6600 2800) BN 9
J 0
(-6612 2808);
DISPLAY 0.680851 (-6612 2808);
PAINT GREEN (-6612 2808);
FORCEPROP 2 LAST CDS_LIB standard
J 0
(-6550 2800);
DISPLAY INVISIBLE (-6550 2800);
FORCEPROP 1 LAST BODY_TYPE PLUMBING
J 0
(-6550 2850);
DISPLAY 0.872340 (-6550 2850);
PAINT GREEN (-6550 2850);
DISPLAY INVISIBLE (-6550 2850);
FORCEPROP 1 LAST HDL_TAP TRUE
J 0
(-6225 2675);
DISPLAY 0.872340 (-6225 2675);
DISPLAY INVISIBLE (-6225 2675);
FORCEPROP 1 LAST PATH I5
J 0
(-6552 2800);
DISPLAY 0.872340 (-6552 2800);
PAINT GREEN (-6552 2800);
DISPLAY INVISIBLE (-6552 2800);
FORCEADD TAP..1
(-6750 3250);
FORCEPROP 3 LASTPIN (-6800 3250) SIG_NAME P5E_CPU1_P3_RX_BUF_DP<10>
J 0
(-6790 3260);
DISPLAY 0.659574 (-6790 3260);
PAINT MONO (-6790 3260);
DISPLAY INVISIBLE (-6790 3260);
FORCEPROP 1 LASTPIN (-6800 3250) BN 10
J 0
(-6812 3258);
DISPLAY 0.680851 (-6812 3258);
PAINT GREEN (-6812 3258);
FORCEPROP 2 LAST CDS_LIB standard
J 0
(-6750 3250);
DISPLAY INVISIBLE (-6750 3250);
FORCEPROP 1 LAST BODY_TYPE PLUMBING
J 0
(-6750 3300);
DISPLAY 0.872340 (-6750 3300);
PAINT GREEN (-6750 3300);
DISPLAY INVISIBLE (-6750 3300);
FORCEPROP 1 LAST HDL_TAP TRUE
J 0
(-6425 3125);
DISPLAY 0.872340 (-6425 3125);
DISPLAY INVISIBLE (-6425 3125);
FORCEPROP 1 LAST PATH I6
J 0
(-6752 3250);
DISPLAY 0.872340 (-6752 3250);
PAINT GREEN (-6752 3250);
DISPLAY INVISIBLE (-6752 3250);
FORCEADD TAP..1
(-6750 3600);
FORCEPROP 3 LASTPIN (-6800 3600) SIG_NAME P5E_CPU1_P3_RX_BUF_DP<11>
J 0
(-6790 3610);
DISPLAY 0.659574 (-6790 3610);
PAINT MONO (-6790 3610);
DISPLAY INVISIBLE (-6790 3610);
FORCEPROP 1 LASTPIN (-6800 3600) BN 11
J 0
(-6812 3608);
DISPLAY 0.680851 (-6812 3608);
PAINT GREEN (-6812 3608);
FORCEPROP 2 LAST CDS_LIB standard
J 0
(-6750 3600);
DISPLAY INVISIBLE (-6750 3600);
FORCEPROP 1 LAST BODY_TYPE PLUMBING
J 0
(-6750 3650);
DISPLAY 0.872340 (-6750 3650);
PAINT GREEN (-6750 3650);
DISPLAY INVISIBLE (-6750 3650);
FORCEPROP 1 LAST HDL_TAP TRUE
J 0
(-6425 3475);
DISPLAY 0.872340 (-6425 3475);
DISPLAY INVISIBLE (-6425 3475);
FORCEPROP 1 LAST PATH I7
J 0
(-6752 3600);
DISPLAY 0.872340 (-6752 3600);
PAINT GREEN (-6752 3600);
DISPLAY INVISIBLE (-6752 3600);
FORCEADD TAP..1
(-6750 3950);
FORCEPROP 3 LASTPIN (-6800 3950) SIG_NAME P5E_CPU1_P3_RX_BUF_DP<12>
J 0
(-6790 3960);
DISPLAY 0.659574 (-6790 3960);
PAINT MONO (-6790 3960);
DISPLAY INVISIBLE (-6790 3960);
FORCEPROP 1 LASTPIN (-6800 3950) BN 12
J 0
(-6812 3958);
DISPLAY 0.680851 (-6812 3958);
PAINT GREEN (-6812 3958);
FORCEPROP 2 LAST CDS_LIB standard
J 0
(-6750 3950);
DISPLAY INVISIBLE (-6750 3950);
FORCEPROP 1 LAST BODY_TYPE PLUMBING
J 0
(-6750 4000);
DISPLAY 0.872340 (-6750 4000);
PAINT GREEN (-6750 4000);
DISPLAY INVISIBLE (-6750 4000);
FORCEPROP 1 LAST HDL_TAP TRUE
J 0
(-6425 3825);
DISPLAY 0.872340 (-6425 3825);
DISPLAY INVISIBLE (-6425 3825);
FORCEPROP 1 LAST PATH I8
J 0
(-6752 3950);
DISPLAY 0.872340 (-6752 3950);
PAINT GREEN (-6752 3950);
DISPLAY INVISIBLE (-6752 3950);
FORCEADD TAP..1
(-6550 3150);
FORCEPROP 3 LASTPIN (-6600 3150) SIG_NAME P5E_CPU1_P3_RX_BUF_DN<10>
J 0
(-6590 3160);
DISPLAY 0.659574 (-6590 3160);
PAINT MONO (-6590 3160);
DISPLAY INVISIBLE (-6590 3160);
FORCEPROP 1 LASTPIN (-6600 3150) BN 10
J 0
(-6612 3158);
DISPLAY 0.680851 (-6612 3158);
PAINT GREEN (-6612 3158);
FORCEPROP 2 LAST CDS_LIB standard
J 0
(-6550 3150);
DISPLAY INVISIBLE (-6550 3150);
FORCEPROP 1 LAST BODY_TYPE PLUMBING
J 0
(-6550 3200);
DISPLAY 0.872340 (-6550 3200);
PAINT GREEN (-6550 3200);
DISPLAY INVISIBLE (-6550 3200);
FORCEPROP 1 LAST HDL_TAP TRUE
J 0
(-6225 3025);
DISPLAY 0.872340 (-6225 3025);
DISPLAY INVISIBLE (-6225 3025);
FORCEPROP 1 LAST PATH I9
J 0
(-6552 3150);
DISPLAY 0.872340 (-6552 3150);
PAINT GREEN (-6552 3150);
DISPLAY INVISIBLE (-6552 3150);
FORCEADD QUANTA_TITLE_BLOCK_C..1
(0 0);
FORCEPROP 0 LAST CDS_CON_LAST_MODIFIED Thu Sep 14 16:12:56 2023
J 0
(-1885 15);
DISPLAY INVISIBLE (-1885 15);
FORCEPROP 1 LAST CUSTOM_TXT_CDS <CON_LAST_MODIFIED>
J 0
(-1885 15);
DISPLAY 0.978723 (-1885 15);
FORCEPROP 2 LAST CUSTOM_TXT_CDS <XR_PAGE_TITLE>
J 0
(-7890 5250);
DISPLAY 0.638298 (-7890 5250);
PAINT PINK (-7890 5250);
DISPLAY INVISIBLE (-7890 5250);
FORCEPROP 1 LAST CUSTOM_TXT_CDS <NAME_2>
J 0
(-3175 50);
FORCEPROP 1 LAST CUSTOM_TXT_CDS <NAME_1>
J 0
(-3175 175);
FORCEPROP 1 LAST CUSTOM_TXT_CDS <Q_NUMBER>
J 0
(-1403 103);
DISPLAY 1.212766 (-1403 103);
FORCEPROP 1 LAST CUSTOM_TXT_CDS <Q_PROJ>
J 0
(-2382 102);
DISPLAY 1.212766 (-2382 102);
FORCEPROP 1 LAST CUSTOM_TXT_CDS <Q_REV>
J 0
(-184 103);
DISPLAY 1.212766 (-184 103);
FORCEPROP 1 LAST CUSTOM_TXT_CDS <CON_PAGE_NUM> OF <CON_TOTAL_PAGES>
J 0
(-446 18);
DISPLAY 0.978723 (-446 18);
FORCEPROP 1 LAST Q_TITLE RETIMER_CPU1_P3(3)
J 0
(-9366 26);
DISPLAY 2.446809 (-9366 26);
PAINT GREEN (-9366 26);
FORCEPROP 2 LAST PAGE_BORDER TRUE
J 0
(-7890 5250);
DISPLAY 0.638298 (-7890 5250);
PAINT PINK (-7890 5250);
DISPLAY INVISIBLE (-7890 5250);
FORCEPROP 1 LAST CDS_LMAN_SYM_OUTLINE -9475,6775,100,-125
J 0
(0 0);
DISPLAY 0.468085 (0 0);
PAINT GREEN (0 0);
DISPLAY INVISIBLE (0 0);
FORCEPROP 2 LAST CDS_LIB pure_quanta
J 0
(0 0);
DISPLAY INVISIBLE (0 0);
FORCEPROP 2 LAST CDS_XR_PAGE_TITLE CR-352 : @T6G_MB_LIB.T6G(SCH_1):PAGE352
J 0
(-7890 5250);
DISPLAY 0.638298 (-7890 5250);
PAINT PINK (-7890 5250);
DISPLAY INVISIBLE (-7890 5250);
FORCEPROP 1 LAST Q_DEPT BU9
J 1
(-3763 49);
DISPLAY 1.957447 (-3763 49);
PAINT GREEN (-3763 49);
DISPLAY INVISIBLE (-3763 49);
FORCEPROP 1 LAST COMMENT_BODY TRUE
J 0
(12 -13);
DISPLAY 0.978723 (12 -13);
PAINT GREEN (12 -13);
DISPLAY INVISIBLE (12 -13);
WIRE 17 -1 (-2250 5125)(-2250 5050);
WIRE 17 -1 (-2250 5125)(-1125 5125);
FORCEPROP 2 LAST SIG_NAME P5E_CPU1_P3_RX_BUF_DP<7:0>
J 0
(-1985 5135);
DISPLAY 0.680851 (-1985 5135);
PAINT WHITE (-1985 5135);
WIRE 17 -1 (-2050 5050)(-2050 4950);
WIRE 17 -1 (-2050 5050)(-1125 5050);
FORCEPROP 2 LAST SIG_NAME P5E_CPU1_P3_RX_BUF_DN<7:0>
J 0
(-1985 5060);
DISPLAY 0.680851 (-1985 5060);
PAINT WHITE (-1985 5060);
WIRE 17 -1 (-2050 2850)(-2050 2500);
WIRE 17 -1 (-2050 3200)(-2050 2850);
WIRE 17 -1 (-2050 3550)(-2050 3200);
WIRE 17 -1 (-2050 3550)(-2050 3900);
WIRE 17 -1 (-2050 4250)(-2050 3900);
WIRE 17 -1 (-2050 4600)(-2050 4250);
WIRE 17 -1 (-2050 4950)(-2050 4600);
WIRE 17 -1 (-2250 5050)(-2250 4700);
WIRE 17 -1 (-2250 4700)(-2250 4350);
WIRE 17 -1 (-2250 4350)(-2250 4000);
WIRE 17 -1 (-2250 2950)(-2250 2600);
WIRE 17 -1 (-2250 3300)(-2250 2950);
WIRE 17 -1 (-2250 3650)(-2250 3300);
WIRE 17 -1 (-2250 3650)(-2250 4000);
WIRE 17 -1 (-6500 2825)(-6500 2475);
WIRE 17 -1 (-6500 3175)(-6500 2825);
WIRE 17 -1 (-6500 3525)(-6500 3175);
WIRE 17 -1 (-6500 3525)(-6500 3875);
WIRE 17 -1 (-6500 4225)(-6500 3875);
WIRE 17 -1 (-6500 4575)(-6500 4225);
WIRE 17 -1 (-6500 4925)(-6500 4575);
WIRE 17 -1 (-6500 5025)(-6500 4925);
WIRE 17 -1 (-6500 5025)(-5575 5025);
FORCEPROP 2 LAST SIG_NAME P5E_CPU1_P3_RX_BUF_DN<15:8>
J 0
(-6435 5035);
DISPLAY 0.680851 (-6435 5035);
PAINT WHITE (-6435 5035);
WIRE 17 -1 (-6700 5025)(-6700 4675);
WIRE 17 -1 (-6700 5100)(-6700 5025);
WIRE 17 -1 (-6700 4675)(-6700 4325);
WIRE 17 -1 (-6700 4325)(-6700 3975);
WIRE 17 -1 (-6700 5100)(-5575 5100);
FORCEPROP 2 LAST SIG_NAME P5E_CPU1_P3_RX_BUF_DP<15:8>
J 0
(-6435 5110);
DISPLAY 0.680851 (-6435 5110);
PAINT WHITE (-6435 5110);
WIRE 17 -1 (-6700 3625)(-6700 3975);
WIRE 17 -1 (-6700 2925)(-6700 2575);
WIRE 17 -1 (-6700 3275)(-6700 2925);
WIRE 17 -1 (-6700 3625)(-6700 3275);
WIRE 16 -1 (-7325 3950)(-6800 3950);
WIRE 16 -1 (-7325 3600)(-6800 3600);
WIRE 16 -1 (-7325 3850)(-6600 3850);
WIRE 16 -1 (-7325 3500)(-6600 3500);
WIRE 16 -1 (-7325 3250)(-6800 3250);
WIRE 16 -1 (-7325 2800)(-6600 2800);
WIRE 16 -1 (-7325 2900)(-6800 2900);
WIRE 16 -1 (-2875 2925)(-2350 2925);
WIRE 16 -1 (-2875 3975)(-2350 3975);
WIRE 16 -1 (-2875 3875)(-2150 3875);
WIRE 16 -1 (-2875 4325)(-2350 4325);
WIRE 16 -1 (-2875 3275)(-2350 3275);
WIRE 16 -1 (-2875 3525)(-2150 3525);
WIRE 16 -1 (-2875 3625)(-2350 3625);
WIRE 16 -1 (-7325 4200)(-6600 4200);
WIRE 16 -1 (-7325 4900)(-6600 4900);
WIRE 16 -1 (-7325 5000)(-6800 5000);
WIRE 16 -1 (-7325 2550)(-6800 2550);
WIRE 16 -1 (-7325 3150)(-6600 3150);
WIRE 16 -1 (-7325 4300)(-6800 4300);
WIRE 16 -1 (-7325 4550)(-6600 4550);
WIRE 16 -1 (-7325 4650)(-6800 4650);
WIRE 16 -1 (-7325 2450)(-6600 2450);
WIRE 16 -1 (-2875 2575)(-2350 2575);
WIRE 16 -1 (-2875 2825)(-2150 2825);
WIRE 16 -1 (-2875 3175)(-2150 3175);
WIRE 16 -1 (-2875 4225)(-2150 4225);
WIRE 16 -1 (-2875 4575)(-2150 4575);
WIRE 16 -1 (-2875 4675)(-2350 4675);
WIRE 16 -1 (-2875 2475)(-2150 2475);
WIRE 16 -1 (-2875 4925)(-2150 4925);
WIRE 16 -1 (-2875 5025)(-2350 5025);
FORCENOTE
P5E_CPU1_P3_RX_BUF_DP/DN<0-15> LANE REVERSAL
(-8975 6375) 0;
DISPLAY LEFT (-8975 6375);
DISPLAY 2.000000 (-8975 6375);
FORCENOTE
EXAMAX TO RETIMER
(-8150 1625) 0;
DISPLAY LEFT (-8150 1625);
DISPLAY 3.148936 (-8150 1625);
FORCENOTE
EXAMAX TO RETIMER
(-3600 1600) 0;
DISPLAY LEFT (-3600 1600);
DISPLAY 3.148936 (-3600 1600);
QUIT
